(kicad_pcb
	(version 20260206)
	(generator "pcbnew")
	(generator_version "10.0")
	(general
		(thickness 1.6)
		(legacy_teardrops no)
	)
	(paper "A4")
	(title_block
		(title "01162023_DA0F0TEBIF0_F0T_Expander_BD_F_brd_V02_OCP.brd")
		(comment 1 "Grand Teton / footprints 7043-7049 of 9728")
	)
	(layers
		(0 "F.Cu" signal "TOP")
		(4 "In1.Cu" signal "GND")
		(6 "In2.Cu" signal "VCC")
		(8 "In3.Cu" signal "VCC1")
		(10 "In4.Cu" signal "GND1")
		(12 "In5.Cu" signal "IN1")
		(14 "In6.Cu" signal "GND2")
		(16 "In7.Cu" signal "IN2")
		(18 "In8.Cu" signal "GND3")
		(20 "In9.Cu" signal "IN3")
		(22 "In10.Cu" signal "GND4")
		(24 "In11.Cu" signal "IN4")
		(26 "In12.Cu" signal "GND5")
		(28 "In13.Cu" signal "IN5")
		(30 "In14.Cu" signal "GND6")
		(32 "In15.Cu" signal "IN6")
		(34 "In16.Cu" signal "GND7")
		(2 "B.Cu" signal "BOTTOM")
		(9 "F.Adhes" user "F.Adhesive")
		(11 "B.Adhes" user "B.Adhesive")
		(13 "F.Paste" user "Package Geometry/Pastemask Top")
		(15 "B.Paste" user "Package Geometry/Pastemask Bottom")
		(5 "F.SilkS" user "Ref Des/Silkscreen Top")
		(7 "B.SilkS" user "Ref Des/Silkscreen Bottom")
		(1 "F.Mask" user "Board Geometry/Soldermask Top")
		(3 "B.Mask" user "Board Geometry/Soldermask Bottom")
		(17 "Dwgs.User" user "User.Drawings")
		(19 "Cmts.User" user "User.Comments")
		(21 "Eco1.User" user "User.Eco1")
		(23 "Eco2.User" user "User.Eco2")
		(25 "Edge.Cuts" user "Board Geometry/Outline")
		(27 "Margin" user)
		(31 "F.CrtYd" user "Package Geometry/Place Bound Top")
		(29 "B.CrtYd" user "Package Geometry/Place Bound Bottom")
		(35 "F.Fab" user "Ref Des/Assembly Top")
		(33 "B.Fab" user "Ref Des/Assembly Bottom")
	)
	(footprint ""
		(layer "F.Cu")
		(at 296.024554 -158.080202 90)
		(property "Reference" "R2476"
			(at 0 0 90)
			(layer "F.SilkS")
			(hide yes)
			(effects
				(font
					(size 1.27 1.27)
				)
			)
		)
		(property "Value" ""
			(at 0 0 90)
			(layer "F.Fab")
			(effects
				(font
					(size 1.27 1.27)
				)
			)
		)
		(duplicate_pad_numbers_are_jumpers no)
		(fp_line
			(start 0.7874 -0.4064)
			(end 0.7874 0.4064)
			(stroke
				(width 0.1524)
				(type default)
			)
			(layer "F.SilkS")
		)
		(fp_line
			(start -0.7874 -0.4064)
			(end 0.7874 -0.4064)
			(stroke
				(width 0.1524)
				(type default)
			)
			(layer "F.SilkS")
		)
		(fp_line
			(start 0.7874 0.4064)
			(end -0.7874 0.4064)
			(stroke
				(width 0.1524)
				(type default)
			)
			(layer "F.SilkS")
		)
		(fp_line
			(start -0.7874 0.4064)
			(end -0.7874 -0.4064)
			(stroke
				(width 0.1524)
				(type default)
			)
			(layer "F.SilkS")
		)
		(fp_line
			(start -0.12065 -0.305054)
			(end -0.12065 -0.2794)
			(stroke
				(width 0.1)
				(type default)
			)
			(layer "F.Fab")
		)
		(fp_line
			(start -0.67945 -0.305054)
			(end -0.12065 -0.305054)
			(stroke
				(width 0.1)
				(type default)
			)
			(layer "F.Fab")
		)
		(fp_line
			(start 0.67945 -0.3048)
			(end 0.67945 0.3048)
			(stroke
				(width 0.1)
				(type default)
			)
			(layer "F.Fab")
		)
		(fp_line
			(start 0.12065 -0.3048)
			(end 0.67945 -0.3048)
			(stroke
				(width 0.1)
				(type default)
			)
			(layer "F.Fab")
		)
		(fp_line
			(start 0.12065 -0.2794)
			(end 0.12065 -0.3048)
			(stroke
				(width 0.1)
				(type default)
			)
			(layer "F.Fab")
		)
		(fp_line
			(start -0.12065 -0.2794)
			(end 0.12065 -0.2794)
			(stroke
				(width 0.1)
				(type default)
			)
			(layer "F.Fab")
		)
		(fp_line
			(start 0.120396 0.2794)
			(end -0.12065 0.2794)
			(stroke
				(width 0.1)
				(type default)
			)
			(layer "F.Fab")
		)
		(fp_line
			(start -0.12065 0.2794)
			(end -0.12065 0.3048)
			(stroke
				(width 0.1)
				(type default)
			)
			(layer "F.Fab")
		)
		(fp_line
			(start 0.67945 0.3048)
			(end 0.120396 0.3048)
			(stroke
				(width 0.1)
				(type default)
			)
			(layer "F.Fab")
		)
		(fp_line
			(start 0.120396 0.3048)
			(end 0.120396 0.2794)
			(stroke
				(width 0.1)
				(type default)
			)
			(layer "F.Fab")
		)
		(fp_line
			(start -0.12065 0.3048)
			(end -0.67945 0.3048)
			(stroke
				(width 0.1)
				(type default)
			)
			(layer "F.Fab")
		)
		(fp_line
			(start -0.67945 0.3048)
			(end -0.67945 -0.305054)
			(stroke
				(width 0.1)
				(type default)
			)
			(layer "F.Fab")
		)
		(pad "1" smd circle
			(at -0.40005 0 90)
			(size 0 0)
			(layers "F.Cu" "F.Mask" "F.Paste")
			(net "NIC5_PWRBRK_R_N")
		)
		(pad "2" smd circle
			(at 0.40005 0 90)
			(size 0 0)
			(layers "F.Cu" "F.Mask" "F.Paste")
			(net "NIC5_PWRBRK_N")
		)
	)
	(footprint ""
		(layer "F.Cu")
		(at 324.01764 -87.42934 -90)
		(property "Reference" "R6384"
			(at 0 0 270)
			(layer "F.SilkS")
			(hide yes)
			(effects
				(font
					(size 1.27 1.27)
				)
			)
		)
		(property "Value" ""
			(at 0 0 270)
			(layer "F.Fab")
			(effects
				(font
					(size 1.27 1.27)
				)
			)
		)
		(duplicate_pad_numbers_are_jumpers no)
		(fp_line
			(start -0.7874 0.4064)
			(end -0.7874 -0.4064)
			(stroke
				(width 0.1524)
				(type default)
			)
			(layer "F.SilkS")
		)
		(fp_line
			(start 0.7874 0.4064)
			(end -0.7874 0.4064)
			(stroke
				(width 0.1524)
				(type default)
			)
			(layer "F.SilkS")
		)
		(fp_line
			(start -0.7874 -0.4064)
			(end 0.7874 -0.4064)
			(stroke
				(width 0.1524)
				(type default)
			)
			(layer "F.SilkS")
		)
		(fp_line
			(start 0.7874 -0.4064)
			(end 0.7874 0.4064)
			(stroke
				(width 0.1524)
				(type default)
			)
			(layer "F.SilkS")
		)
		(fp_line
			(start -0.67945 0.3048)
			(end -0.67945 -0.305054)
			(stroke
				(width 0.1)
				(type default)
			)
			(layer "F.Fab")
		)
		(fp_line
			(start -0.12065 0.3048)
			(end -0.67945 0.3048)
			(stroke
				(width 0.1)
				(type default)
			)
			(layer "F.Fab")
		)
		(fp_line
			(start 0.120396 0.3048)
			(end 0.120396 0.2794)
			(stroke
				(width 0.1)
				(type default)
			)
			(layer "F.Fab")
		)
		(fp_line
			(start 0.67945 0.3048)
			(end 0.120396 0.3048)
			(stroke
				(width 0.1)
				(type default)
			)
			(layer "F.Fab")
		)
		(fp_line
			(start -0.12065 0.2794)
			(end -0.12065 0.3048)
			(stroke
				(width 0.1)
				(type default)
			)
			(layer "F.Fab")
		)
		(fp_line
			(start 0.120396 0.2794)
			(end -0.12065 0.2794)
			(stroke
				(width 0.1)
				(type default)
			)
			(layer "F.Fab")
		)
		(fp_line
			(start -0.12065 -0.2794)
			(end 0.12065 -0.2794)
			(stroke
				(width 0.1)
				(type default)
			)
			(layer "F.Fab")
		)
		(fp_line
			(start 0.12065 -0.2794)
			(end 0.12065 -0.3048)
			(stroke
				(width 0.1)
				(type default)
			)
			(layer "F.Fab")
		)
		(fp_line
			(start 0.12065 -0.3048)
			(end 0.67945 -0.3048)
			(stroke
				(width 0.1)
				(type default)
			)
			(layer "F.Fab")
		)
		(fp_line
			(start 0.67945 -0.3048)
			(end 0.67945 0.3048)
			(stroke
				(width 0.1)
				(type default)
			)
			(layer "F.Fab")
		)
		(fp_line
			(start -0.67945 -0.305054)
			(end -0.12065 -0.305054)
			(stroke
				(width 0.1)
				(type default)
			)
			(layer "F.Fab")
		)
		(fp_line
			(start -0.12065 -0.305054)
			(end -0.12065 -0.2794)
			(stroke
				(width 0.1)
				(type default)
			)
			(layer "F.Fab")
		)
		(pad "1" smd circle
			(at -0.40005 0 270)
			(size 0 0)
			(layers "F.Cu" "F.Mask" "F.Paste")
			(net "SMB_BMC_9FGL0451E_S3_SCL")
		)
		(pad "2" smd circle
			(at 0.40005 0 270)
			(size 0 0)
			(layers "F.Cu" "F.Mask" "F.Paste")
			(net "SMB_ISO_CB_SCL")
		)
	)
	(footprint ""
		(layer "F.Cu")
		(at 296.766742 -343.952322 90)
		(property "Reference" "C588"
			(at 0 0 90)
			(layer "F.SilkS")
			(hide yes)
			(effects
				(font
					(size 1.27 1.27)
				)
			)
		)
		(property "Value" ""
			(at 0 0 90)
			(layer "F.Fab")
			(effects
				(font
					(size 1.27 1.27)
				)
			)
		)
		(duplicate_pad_numbers_are_jumpers no)
		(fp_line
			(start 0.299974 -0.150114)
			(end 0.299974 0.150114)
			(stroke
				(width 0.1)
				(type default)
			)
			(layer "F.Fab")
		)
		(fp_line
			(start -0.299974 -0.150114)
			(end 0.299974 -0.150114)
			(stroke
				(width 0.1)
				(type default)
			)
			(layer "F.Fab")
		)
		(fp_line
			(start 0.299974 0.150114)
			(end -0.299974 0.150114)
			(stroke
				(width 0.1)
				(type default)
			)
			(layer "F.Fab")
		)
		(fp_line
			(start -0.299974 0.150114)
			(end -0.299974 -0.150114)
			(stroke
				(width 0.1)
				(type default)
			)
			(layer "F.Fab")
		)
		(pad "1" smd rect
			(at -0.2667 0 90)
			(size 0.3048 0.381)
			(layers "F.Cu" "F.Mask" "F.Paste")
			(net "P5E_PEX2_STN7_TX_DN<125>")
		)
		(pad "2" smd rect
			(at 0.2667 0 90)
			(size 0.3048 0.381)
			(layers "F.Cu" "F.Mask" "F.Paste")
			(net "P5E_PEX2_STN7_TX_C_DN<125>")
		)
	)
	(footprint ""
		(layer "F.Cu")
		(at 35.518344 -252.356874 -90)
		(property "Reference" "R1234"
			(at 0 0 270)
			(layer "F.SilkS")
			(hide yes)
			(effects
				(font
					(size 1.27 1.27)
				)
			)
		)
		(property "Value" ""
			(at 0 0 270)
			(layer "F.Fab")
			(effects
				(font
					(size 1.27 1.27)
				)
			)
		)
		(duplicate_pad_numbers_are_jumpers no)
		(fp_line
			(start -0.7874 0.4064)
			(end -0.7874 -0.4064)
			(stroke
				(width 0.1524)
				(type default)
			)
			(layer "F.SilkS")
		)
		(fp_line
			(start 0.7874 0.4064)
			(end -0.7874 0.4064)
			(stroke
				(width 0.1524)
				(type default)
			)
			(layer "F.SilkS")
		)
		(fp_line
			(start -0.7874 -0.4064)
			(end 0.7874 -0.4064)
			(stroke
				(width 0.1524)
				(type default)
			)
			(layer "F.SilkS")
		)
		(fp_line
			(start 0.7874 -0.4064)
			(end 0.7874 0.4064)
			(stroke
				(width 0.1524)
				(type default)
			)
			(layer "F.SilkS")
		)
		(fp_line
			(start -0.67945 0.3048)
			(end -0.67945 -0.305054)
			(stroke
				(width 0.1)
				(type default)
			)
			(layer "F.Fab")
		)
		(fp_line
			(start -0.12065 0.3048)
			(end -0.67945 0.3048)
			(stroke
				(width 0.1)
				(type default)
			)
			(layer "F.Fab")
		)
		(fp_line
			(start 0.120396 0.3048)
			(end 0.120396 0.2794)
			(stroke
				(width 0.1)
				(type default)
			)
			(layer "F.Fab")
		)
		(fp_line
			(start 0.67945 0.3048)
			(end 0.120396 0.3048)
			(stroke
				(width 0.1)
				(type default)
			)
			(layer "F.Fab")
		)
		(fp_line
			(start -0.12065 0.2794)
			(end -0.12065 0.3048)
			(stroke
				(width 0.1)
				(type default)
			)
			(layer "F.Fab")
		)
		(fp_line
			(start 0.120396 0.2794)
			(end -0.12065 0.2794)
			(stroke
				(width 0.1)
				(type default)
			)
			(layer "F.Fab")
		)
		(fp_line
			(start -0.12065 -0.2794)
			(end 0.12065 -0.2794)
			(stroke
				(width 0.1)
				(type default)
			)
			(layer "F.Fab")
		)
		(fp_line
			(start 0.12065 -0.2794)
			(end 0.12065 -0.3048)
			(stroke
				(width 0.1)
				(type default)
			)
			(layer "F.Fab")
		)
		(fp_line
			(start 0.12065 -0.3048)
			(end 0.67945 -0.3048)
			(stroke
				(width 0.1)
				(type default)
			)
			(layer "F.Fab")
		)
		(fp_line
			(start 0.67945 -0.3048)
			(end 0.67945 0.3048)
			(stroke
				(width 0.1)
				(type default)
			)
			(layer "F.Fab")
		)
		(fp_line
			(start -0.67945 -0.305054)
			(end -0.12065 -0.305054)
			(stroke
				(width 0.1)
				(type default)
			)
			(layer "F.Fab")
		)
		(fp_line
			(start -0.12065 -0.305054)
			(end -0.12065 -0.2794)
			(stroke
				(width 0.1)
				(type default)
			)
			(layer "F.Fab")
		)
		(pad "1" smd circle
			(at -0.40005 0 270)
			(size 0 0)
			(layers "F.Cu" "F.Mask" "F.Paste")
			(net "GND")
		)
		(pad "2" smd circle
			(at 0.40005 0 270)
			(size 0 0)
			(layers "F.Cu" "F.Mask" "F.Paste")
			(net "PEX0_MODE_SEL12")
		)
	)
	(footprint ""
		(layer "F.Cu")
		(at 85.320124 -20.72005)
		(property "Reference" "H107"
			(at -1.43637 -2.878836 0)
			(unlocked yes)
			(layer "B.SilkS")
			(effects
				(font
					(size 0.7874 0.5842)
					(thickness 0.1524)
				)
				(justify left mirror)
			)
		)
		(property "Value" ""
			(at 0 0 0)
			(layer "F.Fab")
			(effects
				(font
					(size 1.27 1.27)
				)
			)
		)
		(duplicate_pad_numbers_are_jumpers no)
		(pad "1" thru_hole rect
			(at 0 0)
			(size 4.2164 5.0038)
			(drill 2.0066
				(offset 0.099822 0)
			)
			(layers "*.Cu" "*.Mask")
			(remove_unused_layers no)
			(net "Net_8556")
			(clearance -0.8509)
			(padstack
				(mode front_inner_back)
				(layer "Inner"
					(shape circle)
					(size 4.0132 4.0132)
					(clearance -0.7493)
				)
				(layer "B.Cu"
					(shape circle)
					(size 4.0132 4.0132)
					(clearance -0.7493)
				)
			)
		)
	)
	(footprint ""
		(layer "F.Cu")
		(at 448.163188 -415.621216 90)
		(property "Reference" "R5606"
			(at 0 0 90)
			(layer "F.SilkS")
			(hide yes)
			(effects
				(font
					(size 1.27 1.27)
				)
			)
		)
		(property "Value" ""
			(at 0 0 90)
			(layer "F.Fab")
			(effects
				(font
					(size 1.27 1.27)
				)
			)
		)
		(duplicate_pad_numbers_are_jumpers no)
		(fp_line
			(start 0.7874 -0.4064)
			(end 0.7874 0.4064)
			(stroke
				(width 0.1524)
				(type default)
			)
			(layer "F.SilkS")
		)
		(fp_line
			(start -0.7874 -0.4064)
			(end 0.7874 -0.4064)
			(stroke
				(width 0.1524)
				(type default)
			)
			(layer "F.SilkS")
		)
		(fp_line
			(start 0.7874 0.4064)
			(end -0.7874 0.4064)
			(stroke
				(width 0.1524)
				(type default)
			)
			(layer "F.SilkS")
		)
		(fp_line
			(start -0.7874 0.4064)
			(end -0.7874 -0.4064)
			(stroke
				(width 0.1524)
				(type default)
			)
			(layer "F.SilkS")
		)
		(fp_line
			(start -0.12065 -0.305054)
			(end -0.12065 -0.2794)
			(stroke
				(width 0.1)
				(type default)
			)
			(layer "F.Fab")
		)
		(fp_line
			(start -0.67945 -0.305054)
			(end -0.12065 -0.305054)
			(stroke
				(width 0.1)
				(type default)
			)
			(layer "F.Fab")
		)
		(fp_line
			(start 0.67945 -0.3048)
			(end 0.67945 0.3048)
			(stroke
				(width 0.1)
				(type default)
			)
			(layer "F.Fab")
		)
		(fp_line
			(start 0.12065 -0.3048)
			(end 0.67945 -0.3048)
			(stroke
				(width 0.1)
				(type default)
			)
			(layer "F.Fab")
		)
		(fp_line
			(start 0.12065 -0.2794)
			(end 0.12065 -0.3048)
			(stroke
				(width 0.1)
				(type default)
			)
			(layer "F.Fab")
		)
		(fp_line
			(start -0.12065 -0.2794)
			(end 0.12065 -0.2794)
			(stroke
				(width 0.1)
				(type default)
			)
			(layer "F.Fab")
		)
		(fp_line
			(start 0.120396 0.2794)
			(end -0.12065 0.2794)
			(stroke
				(width 0.1)
				(type default)
			)
			(layer "F.Fab")
		)
		(fp_line
			(start -0.12065 0.2794)
			(end -0.12065 0.3048)
			(stroke
				(width 0.1)
				(type default)
			)
			(layer "F.Fab")
		)
		(fp_line
			(start 0.67945 0.3048)
			(end 0.120396 0.3048)
			(stroke
				(width 0.1)
				(type default)
			)
			(layer "F.Fab")
		)
		(fp_line
			(start 0.120396 0.3048)
			(end 0.120396 0.2794)
			(stroke
				(width 0.1)
				(type default)
			)
			(layer "F.Fab")
		)
		(fp_line
			(start -0.12065 0.3048)
			(end -0.67945 0.3048)
			(stroke
				(width 0.1)
				(type default)
			)
			(layer "F.Fab")
		)
		(fp_line
			(start -0.67945 0.3048)
			(end -0.67945 -0.305054)
			(stroke
				(width 0.1)
				(type default)
			)
			(layer "F.Fab")
		)
		(pad "1" smd circle
			(at -0.40005 0 90)
			(size 0 0)
			(layers "F.Cu" "F.Mask" "F.Paste")
			(net "LM75_1_A1")
		)
		(pad "2" smd circle
			(at 0.40005 0 90)
			(size 0 0)
			(layers "F.Cu" "F.Mask" "F.Paste")
			(net "GND")
		)
	)
	(footprint ""
		(layer "F.Cu")
		(at 105.021126 -303.698402 90)
		(property "Reference" "PC88"
			(at 0 0 90)
			(layer "F.SilkS")
			(hide yes)
			(effects
				(font
					(size 1.27 1.27)
				)
			)
		)
		(property "Value" ""
			(at 0 0 90)
			(layer "F.Fab")
			(effects
				(font
					(size 1.27 1.27)
				)
			)
		)
		(duplicate_pad_numbers_are_jumpers no)
		(fp_line
			(start -4.53898 -2.150618)
			(end -4.539742 2.152142)
			(stroke
				(width 0.1524)
				(type default)
			)
			(layer "F.SilkS")
		)
		(fp_line
			(start -4.69138 -2.150618)
			(end -4.692396 2.161032)
			(stroke
				(width 0.1524)
				(type default)
			)
			(layer "F.SilkS")
		)
		(fp_line
			(start -4.84378 -2.150618)
			(end -4.53898 -2.150618)
			(stroke
				(width 0.1524)
				(type default)
			)
			(layer "F.SilkS")
		)
		(fp_line
			(start -4.84378 -2.150618)
			(end -4.842256 2.163064)
			(stroke
				(width 0.1524)
				(type default)
			)
			(layer "F.SilkS")
		)
		(fp_line
			(start 4.53898 -2.15011)
			(end 4.53898 2.15011)
			(stroke
				(width 0.1524)
				(type default)
			)
			(layer "F.SilkS")
		)
		(fp_line
			(start -4.53898 -2.15011)
			(end 4.53898 -2.15011)
			(stroke
				(width 0.1524)
				(type default)
			)
			(layer "F.SilkS")
		)
		(fp_line
			(start 4.53898 2.15011)
			(end -4.53898 2.15011)
			(stroke
				(width 0.1524)
				(type default)
			)
			(layer "F.SilkS")
		)
		(fp_line
			(start -4.53898 2.15011)
			(end -4.53898 -2.15011)
			(stroke
				(width 0.1524)
				(type default)
			)
			(layer "F.SilkS")
		)
		(fp_line
			(start -4.83108 2.150364)
			(end -4.447794 2.149348)
			(stroke
				(width 0.1524)
				(type default)
			)
			(layer "F.SilkS")
		)
		(fp_line
			(start 3.64998 -2.15011)
			(end 3.64998 2.15011)
			(stroke
				(width 0.1)
				(type default)
			)
			(layer "F.Fab")
		)
		(fp_line
			(start -3.64998 -2.15011)
			(end 3.64998 -2.15011)
			(stroke
				(width 0.1)
				(type default)
			)
			(layer "F.Fab")
		)
		(fp_line
			(start 3.64998 2.15011)
			(end -3.64998 2.15011)
			(stroke
				(width 0.1)
				(type default)
			)
			(layer "F.Fab")
		)
		(fp_line
			(start -3.64998 2.15011)
			(end -3.64998 -2.15011)
			(stroke
				(width 0.1)
				(type default)
			)
			(layer "F.Fab")
		)
		(fp_text user "+"
			(at -5.12191 -3.164078 90)
			(unlocked yes)
			(layer "F.SilkS")
			(effects
				(font
					(size 1.905 1.4224)
					(thickness 0.1524)
				)
				(justify left)
			)
		)
		(fp_text user "-"
			(at 4.685284 -0.437134 90)
			(unlocked yes)
			(layer "F.SilkS")
			(effects
				(font
					(size 1.905 1.4224)
					(thickness 0.1524)
				)
				(justify left)
			)
		)
		(fp_text user "+"
			(at -6.214872 -0.337058 90)
			(unlocked yes)
			(layer "F.Fab")
			(effects
				(font
					(size 1.905 1.4224)
					(thickness 0.1524)
				)
				(justify left)
			)
		)
		(fp_text user "-"
			(at 4.313174 -0.094488 90)
			(unlocked yes)
			(layer "F.Fab")
			(effects
				(font
					(size 1.905 1.4224)
					(thickness 0.1524)
				)
				(justify left)
			)
		)
		(pad "1" smd rect
			(at -3.199892 0 90)
			(size 2.413 2.8194)
			(layers "F.Cu" "F.Mask" "F.Paste")
			(net "P0V8_PEX0")
		)
		(pad "2" smd rect
			(at 3.199892 0 90)
			(size 2.413 2.8194)
			(layers "F.Cu" "F.Mask" "F.Paste")
			(net "GND")
		)
	)
)
